(kicad_pcb
	(version 20260206)
	(generator "pcbnew")
	(generator_version "10.0")
	(general
		(thickness 1.6)
		(legacy_teardrops no)
	)
	(paper "A4")
	(title_block
		(title "panther-plus-userver — 13130-1b_20150205.brd")
		(comment 1 "Honey Badger (Wiwynn) / footprints 359-364 of 1509")
	)
	(layers
		(0 "F.Cu" signal "TOP")
		(4 "In1.Cu" signal "L2")
		(6 "In2.Cu" signal "L3")
		(8 "In3.Cu" signal "L4")
		(10 "In4.Cu" signal "L5")
		(12 "In5.Cu" signal "L6")
		(14 "In6.Cu" signal "L7")
		(16 "In7.Cu" signal "L8")
		(18 "In8.Cu" signal "L9")
		(20 "In9.Cu" signal "L10")
		(22 "In10.Cu" signal "L11")
		(2 "B.Cu" signal "BOTTOM")
		(9 "F.Adhes" user "F.Adhesive")
		(11 "B.Adhes" user "B.Adhesive")
		(13 "F.Paste" user "Package Geometry/Pastemask Top")
		(15 "B.Paste" user "Package Geometry/Pastemask Bottom")
		(5 "F.SilkS" user "Ref Des/Silkscreen Top")
		(7 "B.SilkS" user "Ref Des/Silkscreen Bottom")
		(1 "F.Mask" user "Board Geometry/Soldermask Top")
		(3 "B.Mask" user "Board Geometry/Soldermask Bottom")
		(17 "Dwgs.User" user "User.Drawings")
		(19 "Cmts.User" user "User.Comments")
		(21 "Eco1.User" user "User.Eco1")
		(23 "Eco2.User" user "User.Eco2")
		(25 "Edge.Cuts" user "Board Geometry/Outline")
		(27 "Margin" user)
		(31 "F.CrtYd" user "Package Geometry/Place Bound Top")
		(29 "B.CrtYd" user "Package Geometry/Place Bound Bottom")
		(35 "F.Fab" user "Ref Des/Assembly Top")
		(33 "B.Fab" user "Ref Des/Assembly Bottom")
	)
	(footprint ""
		(layer "F.Cu")
		(at 74.295 -13.462 90)
		(property "Reference" "Q15"
			(at 0 0 90)
			(layer "F.SilkS")
			(hide yes)
			(effects
				(font
					(size 1.27 1.27)
				)
			)
		)
		(property "Value" "2N7002A-7-GP"
			(at -4.3561 -5.7912 90)
			(unlocked yes)
			(layer "F.Fab")
			(hide yes)
			(effects
				(font
					(size 1.016 1.016)
					(thickness 0.1524)
				)
			)
		)
		(property "Device Type" "SOT23DGS2D4H48"
			(at -4.3561 -7.3152 90)
			(unlocked yes)
			(layer "F.Fab")
			(hide yes)
			(effects
				(font
					(size 1.016 1.016)
					(thickness 0.1524)
				)
			)
		)
		(duplicate_pad_numbers_are_jumpers no)
		(fp_line
			(start 1.7145 -0.4445)
			(end -1.7145 -0.4445)
			(stroke
				(width 0.1524)
				(type default)
			)
			(layer "F.SilkS")
		)
		(fp_line
			(start -1.7145 -0.4445)
			(end -1.7145 0.4445)
			(stroke
				(width 0.1524)
				(type default)
			)
			(layer "F.SilkS")
		)
		(fp_line
			(start 1.7145 0.4445)
			(end 1.7145 -0.4445)
			(stroke
				(width 0.1524)
				(type default)
			)
			(layer "F.SilkS")
		)
		(fp_line
			(start -1.7145 0.4445)
			(end 1.7145 0.4445)
			(stroke
				(width 0.1524)
				(type default)
			)
			(layer "F.SilkS")
		)
		(fp_poly
			(pts
				(xy -1.4224 1.5621) (xy -1.4224 0.9017) (xy -1.7145 0.9017) (xy -1.7145 -0.9017) (xy -0.4699 -0.9017)
				(xy -0.4699 -1.5621) (xy 0.4699 -1.5621) (xy 0.4699 -0.9017) (xy 1.7145 -0.9017) (xy 1.7145 0.9017)
				(xy 1.4224 0.9017) (xy 1.4224 1.5621) (xy 0.4826 1.5621) (xy 0.4826 0.9017) (xy -0.4826 0.9017)
				(xy -0.4826 1.5621)
			)
			(stroke
				(width 0)
				(type default)
			)
			(fill no)
			(layer "F.CrtYd")
		)
		(fp_poly
			(pts
				(xy -1.4224 1.5621) (xy -1.4224 0.9017) (xy -1.7145 0.9017) (xy -1.7145 -0.9017) (xy -0.4699 -0.9017)
				(xy -0.4699 -1.5621) (xy 0.4699 -1.5621) (xy 0.4699 -0.9017) (xy 1.7145 -0.9017) (xy 1.7145 0.9017)
				(xy 1.4224 0.9017) (xy 1.4224 1.5621) (xy 0.4826 1.5621) (xy 0.4826 0.9017) (xy -0.4826 0.9017)
				(xy -0.4826 1.5621)
			)
			(stroke
				(width 0)
				(type default)
			)
			(fill no)
			(layer "F.Fab")
		)
		(pad "D" smd custom
			(at 0 -1.069086 90)
			(size 0.17145 0.17145)
			(layers "F.Cu" "F.Mask" "F.Paste")
			(net "PCIE_GF_I2C_ALERT#")
			(options
				(clearance outline)
				(anchor circle)
			)
			(primitives
				(gr_poly
					(pts
						(arc
							(start -0.1397 0.3683)
							(mid -0.283384 0.308784)
							(end -0.3429 0.1651)
						)
						(arc
							(start -0.3429 -0.1651)
							(mid -0.283384 -0.308784)
							(end -0.1397 -0.3683)
						)
						(arc
							(start 0.1397 -0.3683)
							(mid 0.283384 -0.308784)
							(end 0.3429 -0.1651)
						)
						(arc
							(start 0.3429 0.1651)
							(mid 0.283384 0.308784)
							(end 0.1397 0.3683)
						)
					)
					(width 0)
					(fill yes)
				)
			)
		)
		(pad "G" smd custom
			(at -0.94996 1.069086 90)
			(size 0.17145 0.17145)
			(layers "F.Cu" "F.Mask" "F.Paste")
			(net "PICE_GF_I2C_SW_EN")
			(options
				(clearance outline)
				(anchor circle)
			)
			(primitives
				(gr_poly
					(pts
						(arc
							(start -0.1397 0.3683)
							(mid -0.283384 0.308784)
							(end -0.3429 0.1651)
						)
						(arc
							(start -0.3429 -0.1651)
							(mid -0.283384 -0.308784)
							(end -0.1397 -0.3683)
						)
						(arc
							(start 0.1397 -0.3683)
							(mid 0.283384 -0.308784)
							(end 0.3429 -0.1651)
						)
						(arc
							(start 0.3429 0.1651)
							(mid 0.283384 0.308784)
							(end 0.1397 0.3683)
						)
					)
					(width 0)
					(fill yes)
				)
			)
		)
		(pad "S" smd custom
			(at 0.94996 1.069086 90)
			(size 0.17145 0.17145)
			(layers "F.Cu" "F.Mask" "F.Paste")
			(net "BMC_I2C_ALERT#")
			(options
				(clearance outline)
				(anchor circle)
			)
			(primitives
				(gr_poly
					(pts
						(arc
							(start -0.1397 0.3683)
							(mid -0.283384 0.308784)
							(end -0.3429 0.1651)
						)
						(arc
							(start -0.3429 -0.1651)
							(mid -0.283384 -0.308784)
							(end -0.1397 -0.3683)
						)
						(arc
							(start 0.1397 -0.3683)
							(mid 0.283384 -0.308784)
							(end 0.3429 -0.1651)
						)
						(arc
							(start 0.3429 0.1651)
							(mid 0.283384 0.308784)
							(end 0.1397 0.3683)
						)
					)
					(width 0)
					(fill yes)
				)
			)
		)
	)
	(footprint ""
		(layer "F.Cu")
		(at 184.404 -46.101 180)
		(property "Reference" "R218"
			(at 0 0 180)
			(layer "F.SilkS")
			(hide yes)
			(effects
				(font
					(size 1.27 1.27)
				)
			)
		)
		(property "Value" "0R2J-2-GP"
			(at 0.064008 -3.993896 180)
			(unlocked yes)
			(layer "F.Fab")
			(hide yes)
			(effects
				(font
					(size 1.016 1.016)
					(thickness 0.1524)
				)
			)
		)
		(property "Device Type" "R402H16"
			(at 0.064008 -5.517896 180)
			(unlocked yes)
			(layer "F.Fab")
			(hide yes)
			(effects
				(font
					(size 1.016 1.016)
					(thickness 0.1524)
				)
			)
		)
		(duplicate_pad_numbers_are_jumpers no)
		(fp_rect
			(start -0.381 0.8382)
			(end 0.381 -0.8382)
			(stroke
				(width 0)
				(type default)
			)
			(fill no)
			(layer "F.CrtYd")
		)
		(fp_rect
			(start -0.381 0.8382)
			(end 0.381 -0.8382)
			(stroke
				(width 0)
				(type default)
			)
			(fill no)
			(layer "F.Fab")
		)
		(pad "1" smd custom
			(at 0 -0.4318 180)
			(size 0.127 0.127)
			(layers "F.Cu" "F.Mask" "F.Paste")
			(net "SMB_HOST_LV_DATA")
			(options
				(clearance outline)
				(anchor circle)
			)
			(primitives
				(gr_poly
					(pts
						(arc
							(start -0.2032 -0.2794)
							(mid -0.239121 -0.264521)
							(end -0.254 -0.2286)
						)
						(arc
							(start -0.254 0.2286)
							(mid -0.239121 0.264521)
							(end -0.2032 0.2794)
						)
						(arc
							(start 0.2032 0.2794)
							(mid 0.239121 0.264521)
							(end 0.254 0.2286)
						)
						(arc
							(start 0.254 -0.2286)
							(mid 0.239121 -0.264521)
							(end 0.2032 -0.2794)
						)
					)
					(width 0)
					(fill yes)
				)
			)
		)
		(pad "2" smd custom
			(at 0 0.4318 180)
			(size 0.127 0.127)
			(layers "F.Cu" "F.Mask" "F.Paste")
			(net "SMB_DPOT_DATA")
			(options
				(clearance outline)
				(anchor circle)
			)
			(primitives
				(gr_poly
					(pts
						(arc
							(start -0.2032 -0.2794)
							(mid -0.239121 -0.264521)
							(end -0.254 -0.2286)
						)
						(arc
							(start -0.254 0.2286)
							(mid -0.239121 0.264521)
							(end -0.2032 0.2794)
						)
						(arc
							(start 0.2032 0.2794)
							(mid 0.239121 0.264521)
							(end 0.254 0.2286)
						)
						(arc
							(start 0.254 -0.2286)
							(mid 0.239121 -0.264521)
							(end 0.2032 -0.2794)
						)
					)
					(width 0)
					(fill yes)
				)
			)
		)
	)
	(footprint ""
		(layer "F.Cu")
		(at 185.039 -14.986 90)
		(property "Reference" "PC118"
			(at 0 0 90)
			(layer "F.SilkS")
			(hide yes)
			(effects
				(font
					(size 1.27 1.27)
				)
			)
		)
		(property "Value" "SC10U6D3V3MX-GP"
			(at 0 -2.8194 90)
			(unlocked yes)
			(layer "F.Fab")
			(hide yes)
			(effects
				(font
					(size 1.016 1.016)
					(thickness 0.1524)
				)
			)
		)
		(property "Device Type" "C603H38"
			(at 0 -4.3434 90)
			(unlocked yes)
			(layer "F.Fab")
			(hide yes)
			(effects
				(font
					(size 1.016 1.016)
					(thickness 0.1524)
				)
			)
		)
		(duplicate_pad_numbers_are_jumpers no)
		(fp_line
			(start -0.4064 0)
			(end 0.4064 0)
			(stroke
				(width 0.2286)
				(type default)
			)
			(layer "F.SilkS")
		)
		(fp_rect
			(start -0.635 1.1811)
			(end 0.635 -1.1811)
			(stroke
				(width 0)
				(type default)
			)
			(fill no)
			(layer "F.CrtYd")
		)
		(fp_rect
			(start -0.635 1.1811)
			(end 0.635 -1.1811)
			(stroke
				(width 0)
				(type default)
			)
			(fill no)
			(layer "F.Fab")
		)
		(pad "1" smd custom
			(at 0 -0.6604 90)
			(size 0.19685 0.19685)
			(layers "F.Cu" "F.Mask" "F.Paste")
			(net "GND")
			(options
				(clearance outline)
				(anchor circle)
			)
			(primitives
				(gr_poly
					(pts
						(arc
							(start 0.508 -0.2921)
							(mid 0.478242 -0.363942)
							(end 0.4064 -0.3937)
						)
						(arc
							(start -0.4064 -0.3937)
							(mid -0.478242 -0.363942)
							(end -0.508 -0.2921)
						)
						(arc
							(start -0.508 0.2921)
							(mid -0.478242 0.363942)
							(end -0.4064 0.3937)
						)
						(arc
							(start 0.4064 0.3937)
							(mid 0.478242 0.363942)
							(end 0.508 0.2921)
						)
					)
					(width 0)
					(fill yes)
				)
			)
		)
		(pad "2" smd custom
			(at 0 0.6604 90)
			(size 0.19685 0.19685)
			(layers "F.Cu" "F.Mask" "F.Paste")
			(net "PV_VTT_DDR_B")
			(options
				(clearance outline)
				(anchor circle)
			)
			(primitives
				(gr_poly
					(pts
						(arc
							(start 0.508 -0.2921)
							(mid 0.478242 -0.363942)
							(end 0.4064 -0.3937)
						)
						(arc
							(start -0.4064 -0.3937)
							(mid -0.478242 -0.363942)
							(end -0.508 -0.2921)
						)
						(arc
							(start -0.508 0.2921)
							(mid -0.478242 0.363942)
							(end -0.4064 0.3937)
						)
						(arc
							(start 0.4064 0.3937)
							(mid 0.478242 0.363942)
							(end 0.508 0.2921)
						)
					)
					(width 0)
					(fill yes)
				)
			)
		)
	)
	(footprint ""
		(layer "F.Cu")
		(at 74.1172 -61.4426 -90)
		(property "Reference" "U19"
			(at 0 0 270)
			(layer "F.SilkS")
			(hide yes)
			(effects
				(font
					(size 1.27 1.27)
				)
			)
		)
		(property "Value" "ADS7828E-2K5-GP"
			(at 0.127 -12.573 270)
			(unlocked yes)
			(layer "F.Fab")
			(hide yes)
			(effects
				(font
					(size 1.016 1.016)
					(thickness 0.1524)
				)
			)
		)
		(property "Device Type" "TSOIC16H48"
			(at 0.1016 -14.5796 270)
			(unlocked yes)
			(layer "F.Fab")
			(hide yes)
			(effects
				(font
					(size 1.016 1.016)
					(thickness 0.1524)
				)
			)
		)
		(duplicate_pad_numbers_are_jumpers no)
		(fp_line
			(start -2.7305 1.8288)
			(end -2.7305 3.4544)
			(stroke
				(width 0.254)
				(type default)
			)
			(layer "F.SilkS")
		)
		(fp_line
			(start -2.6797 1.778)
			(end -2.6797 -1.778)
			(stroke
				(width 0.1524)
				(type default)
			)
			(layer "F.SilkS")
		)
		(fp_line
			(start 2.37617 1.778)
			(end -2.6797 1.778)
			(stroke
				(width 0.1524)
				(type default)
			)
			(layer "F.SilkS")
		)
		(fp_line
			(start -2.2987 0.0254)
			(end -2.6797 0.4064)
			(stroke
				(width 0.1524)
				(type default)
			)
			(layer "F.SilkS")
		)
		(fp_line
			(start -2.6797 -0.3556)
			(end -2.2987 0.0254)
			(stroke
				(width 0.1524)
				(type default)
			)
			(layer "F.SilkS")
		)
		(fp_line
			(start -2.6797 -1.778)
			(end 2.37617 -1.778)
			(stroke
				(width 0.1524)
				(type default)
			)
			(layer "F.SilkS")
		)
		(fp_line
			(start 2.37617 -1.778)
			(end 2.37617 1.778)
			(stroke
				(width 0.1524)
				(type default)
			)
			(layer "F.SilkS")
		)
		(fp_poly
			(pts
				(xy -2.45237 1.778) (xy 2.37617 1.778) (xy 2.37617 -1.778) (xy -2.45237 -1.778)
			)
			(stroke
				(width 0)
				(type default)
			)
			(fill yes)
			(layer "F.SilkS")
		)
		(fp_rect
			(start -2.7559 3.5814)
			(end 2.7559 -3.5814)
			(stroke
				(width 0)
				(type default)
			)
			(fill no)
			(layer "F.CrtYd")
		)
		(fp_rect
			(start -2.7559 3.5814)
			(end 2.7559 -3.5814)
			(stroke
				(width 0)
				(type default)
			)
			(fill no)
			(layer "F.Fab")
		)
		(pad "1" smd rect
			(at -2.27457 2.7559 270)
			(size 0.3556 1.397)
			(layers "F.Cu" "F.Mask" "F.Paste")
			(net "P12V_SENSE")
		)
		(pad "2" smd rect
			(at -1.6256 2.7559 270)
			(size 0.3556 1.397)
			(layers "F.Cu" "F.Mask" "F.Paste")
			(net "P3V3_STBY_SENSE")
		)
		(pad "3" smd rect
			(at -0.97536 2.7559 270)
			(size 0.3556 1.397)
			(layers "F.Cu" "F.Mask" "F.Paste")
			(net "P3V3_SENSE")
		)
		(pad "4" smd rect
			(at -0.32512 2.7559 270)
			(size 0.3556 1.397)
			(layers "F.Cu" "F.Mask" "F.Paste")
			(net "P1V8_SENSE")
		)
		(pad "5" smd rect
			(at 0.32512 2.7559 270)
			(size 0.3556 1.397)
			(layers "F.Cu" "F.Mask" "F.Paste")
			(net "PVCCP_SENSE")
		)
		(pad "6" smd rect
			(at 0.97536 2.7559 270)
			(size 0.3556 1.397)
			(layers "F.Cu" "F.Mask" "F.Paste")
			(net "PVNN_SENSE")
		)
		(pad "7" smd rect
			(at 1.6256 2.7559 270)
			(size 0.3556 1.397)
			(layers "F.Cu" "F.Mask" "F.Paste")
			(net "P1V0_SENSE")
		)
		(pad "8" smd rect
			(at 2.27457 2.7559 270)
			(size 0.3556 1.397)
			(layers "F.Cu" "F.Mask" "F.Paste")
			(net "PV_VDDR_SENSE")
		)
		(pad "9" smd rect
			(at 2.27457 -2.7559 270)
			(size 0.3556 1.397)
			(layers "F.Cu" "F.Mask" "F.Paste")
			(net "GND")
		)
		(pad "10" smd rect
			(at 1.6256 -2.7559 270)
			(size 0.3556 1.397)
			(layers "F.Cu" "F.Mask" "F.Paste")
			(net "VOL1_SEN_VREF")
		)
		(pad "11" smd rect
			(at 0.97536 -2.7559 270)
			(size 0.3556 1.397)
			(layers "F.Cu" "F.Mask" "F.Paste")
			(net "GND")
		)
		(pad "12" smd rect
			(at 0.32512 -2.7559 270)
			(size 0.3556 1.397)
			(layers "F.Cu" "F.Mask" "F.Paste")
			(net "VOL1_SEN_ADDR0")
		)
		(pad "13" smd rect
			(at -0.32512 -2.7559 270)
			(size 0.3556 1.397)
			(layers "F.Cu" "F.Mask" "F.Paste")
			(net "VOL1_SEN_ADDR1")
		)
		(pad "14" smd rect
			(at -0.97536 -2.7559 270)
			(size 0.3556 1.397)
			(layers "F.Cu" "F.Mask" "F.Paste")
			(net "VOL1_SEN_CLK")
		)
		(pad "15" smd rect
			(at -1.6256 -2.7559 270)
			(size 0.3556 1.397)
			(layers "F.Cu" "F.Mask" "F.Paste")
			(net "VOL1_SEN_DATA")
		)
		(pad "16" smd rect
			(at -2.27457 -2.7559 270)
			(size 0.3556 1.397)
			(layers "F.Cu" "F.Mask" "F.Paste")
			(net "P3V3_STBY")
		)
	)
	(footprint ""
		(layer "F.Cu")
		(at 12.1412 -54.0258 90)
		(property "Reference" "C55"
			(at 0 0 90)
			(layer "F.SilkS")
			(hide yes)
			(effects
				(font
					(size 1.27 1.27)
				)
			)
		)
		(property "Value" "SCD1U16V2KX-3GP"
			(at 1.1811 -2.7051 90)
			(unlocked yes)
			(layer "F.Fab")
			(hide yes)
			(effects
				(font
					(size 1.016 1.016)
					(thickness 0.1524)
				)
			)
		)
		(property "Device Type" "C402H22"
			(at 1.1811 -4.2291 90)
			(unlocked yes)
			(layer "F.Fab")
			(hide yes)
			(effects
				(font
					(size 1.016 1.016)
					(thickness 0.1524)
				)
			)
		)
		(duplicate_pad_numbers_are_jumpers no)
		(fp_rect
			(start -0.381 0.7366)
			(end 0.381 -0.7366)
			(stroke
				(width 0)
				(type default)
			)
			(fill no)
			(layer "F.CrtYd")
		)
		(fp_rect
			(start -0.381 0.7366)
			(end 0.381 -0.7366)
			(stroke
				(width 0)
				(type default)
			)
			(fill no)
			(layer "F.Fab")
		)
		(pad "1" smd custom
			(at 0 -0.4572 90)
			(size 0.1143 0.1143)
			(layers "F.Cu" "F.Mask" "F.Paste")
			(net "P2E_CPU_NGFF_C_RX_DN12")
			(options
				(clearance outline)
				(anchor circle)
			)
			(primitives
				(gr_poly
					(pts
						(arc
							(start -0.254 -0.1778)
							(mid -0.239121 -0.213721)
							(end -0.2032 -0.2286)
						)
						(arc
							(start 0.2032 -0.2286)
							(mid 0.239121 -0.213721)
							(end 0.254 -0.1778)
						)
						(arc
							(start 0.254 0.1778)
							(mid 0.239121 0.213721)
							(end 0.2032 0.2286)
						)
						(arc
							(start -0.2032 0.2286)
							(mid -0.239121 0.213721)
							(end -0.254 0.1778)
						)
					)
					(width 0)
					(fill yes)
				)
			)
		)
		(pad "2" smd custom
			(at 0 0.4572 90)
			(size 0.1143 0.1143)
			(layers "F.Cu" "F.Mask" "F.Paste")
			(net "P2E_CPU_NGFF_RX_DN12")
			(options
				(clearance outline)
				(anchor circle)
			)
			(primitives
				(gr_poly
					(pts
						(arc
							(start -0.254 -0.1778)
							(mid -0.239121 -0.213721)
							(end -0.2032 -0.2286)
						)
						(arc
							(start 0.2032 -0.2286)
							(mid 0.239121 -0.213721)
							(end 0.254 -0.1778)
						)
						(arc
							(start 0.254 0.1778)
							(mid 0.239121 0.213721)
							(end 0.2032 0.2286)
						)
						(arc
							(start -0.2032 0.2286)
							(mid -0.239121 0.213721)
							(end -0.254 0.1778)
						)
					)
					(width 0)
					(fill yes)
				)
			)
		)
	)
	(footprint ""
		(layer "F.Cu")
		(at 132.842 -59.944 90)
		(property "Reference" "PC45"
			(at 0 0 90)
			(layer "F.SilkS")
			(hide yes)
			(effects
				(font
					(size 1.27 1.27)
				)
			)
		)
		(property "Value" "SC10U6D3V3MX-GP"
			(at 0 -2.8194 90)
			(unlocked yes)
			(layer "F.Fab")
			(hide yes)
			(effects
				(font
					(size 1.016 1.016)
					(thickness 0.1524)
				)
			)
		)
		(property "Device Type" "C603H38"
			(at 0 -4.3434 90)
			(unlocked yes)
			(layer "F.Fab")
			(hide yes)
			(effects
				(font
					(size 1.016 1.016)
					(thickness 0.1524)
				)
			)
		)
		(duplicate_pad_numbers_are_jumpers no)
		(fp_line
			(start -0.4064 0)
			(end 0.4064 0)
			(stroke
				(width 0.2286)
				(type default)
			)
			(layer "F.SilkS")
		)
		(fp_rect
			(start -0.635 1.1811)
			(end 0.635 -1.1811)
			(stroke
				(width 0)
				(type default)
			)
			(fill no)
			(layer "F.CrtYd")
		)
		(fp_rect
			(start -0.635 1.1811)
			(end 0.635 -1.1811)
			(stroke
				(width 0)
				(type default)
			)
			(fill no)
			(layer "F.Fab")
		)
		(pad "1" smd custom
			(at 0 -0.6604 90)
			(size 0.19685 0.19685)
			(layers "F.Cu" "F.Mask" "F.Paste")
			(net "GND")
			(options
				(clearance outline)
				(anchor circle)
			)
			(primitives
				(gr_poly
					(pts
						(arc
							(start 0.508 -0.2921)
							(mid 0.478242 -0.363942)
							(end 0.4064 -0.3937)
						)
						(arc
							(start -0.4064 -0.3937)
							(mid -0.478242 -0.363942)
							(end -0.508 -0.2921)
						)
						(arc
							(start -0.508 0.2921)
							(mid -0.478242 0.363942)
							(end -0.4064 0.3937)
						)
						(arc
							(start 0.4064 0.3937)
							(mid 0.478242 0.363942)
							(end 0.508 0.2921)
						)
					)
					(width 0)
					(fill yes)
				)
			)
		)
		(pad "2" smd custom
			(at 0 0.6604 90)
			(size 0.19685 0.19685)
			(layers "F.Cu" "F.Mask" "F.Paste")
			(net "PV_VDDR")
			(options
				(clearance outline)
				(anchor circle)
			)
			(primitives
				(gr_poly
					(pts
						(arc
							(start 0.508 -0.2921)
							(mid 0.478242 -0.363942)
							(end 0.4064 -0.3937)
						)
						(arc
							(start -0.4064 -0.3937)
							(mid -0.478242 -0.363942)
							(end -0.508 -0.2921)
						)
						(arc
							(start -0.508 0.2921)
							(mid -0.478242 0.363942)
							(end -0.4064 0.3937)
						)
						(arc
							(start 0.4064 0.3937)
							(mid 0.478242 0.363942)
							(end 0.508 0.2921)
						)
					)
					(width 0)
					(fill yes)
				)
			)
		)
	)
)
